# T6G (Grand Teton) — schematic netlist excerpt (pin names and nets, part order shuffled) for the footprints in the layout excerpt that follows; sources: Cadence DE-HDL packaged netlist, KiCad conversion of 04192023_DAF0TMB3IC0_F0TG_MB_C_brd_V02_OCP.brd

C463  Q_CAP  0.1UF 10V 10% X7S  pkg C0201  page 356 : A = P0V9_CPU1_RT3_2A_2D ; B = GND
PR83  Q_RES  0 5% CHIP  pkg 0402LF  page 201 : A = PVDDCR_CPU1_P0_VOS2 ; B = PVDDCR_CPU1_P0
C280  Q_CAP  1UF 4V 20% X6S  pkg 0201  page 323 : A = P0V9_CPU1_RT0_2A ; B = GND
PC589_1  Q_CAP  22UF 16V 20% X6S  pkg C0805  page 198 : A = SW_P12V_AUX_PVDDCR_SOC_P0_FLT ; B = GND

(kicad_pcb
	(version 20260206)
	(generator "pcbnew")
	(generator_version "10.0")
	(general
		(thickness 1.6)
		(legacy_teardrops no)
	)
	(paper "A4")
	(title_block
		(title "04192023_DAF0TMB3IC0_F0TG_MB_C_brd_V02_OCP.brd")
		(comment 1 "Grand Teton / footprints 5359-5362 of 8354")
	)
	(layers
		(0 "F.Cu" signal "TOP")
		(4 "In1.Cu" signal "GND")
		(6 "In2.Cu" signal "IN1")
		(8 "In3.Cu" signal "GND1")
		(10 "In4.Cu" signal "IN2")
		(12 "In5.Cu" signal "GND2")
		(14 "In6.Cu" signal "IN3")
		(16 "In7.Cu" signal "GND3")
		(18 "In8.Cu" signal "VCC")
		(20 "In9.Cu" signal "VCC1")
		(22 "In10.Cu" signal "GND4")
		(24 "In11.Cu" signal "IN4")
		(26 "In12.Cu" signal "GND5")
		(28 "In13.Cu" signal "IN5")
		(30 "In14.Cu" signal "GND6")
		(32 "In15.Cu" signal "IN6")
		(34 "In16.Cu" signal "GND7")
		(2 "B.Cu" signal "BOTTOM")
		(9 "F.Adhes" user "F.Adhesive")
		(11 "B.Adhes" user "B.Adhesive")
		(13 "F.Paste" user "Package Geometry/Pastemask Top")
		(15 "B.Paste" user "Package Geometry/Pastemask Bottom")
		(5 "F.SilkS" user "Ref Des/Silkscreen Top")
		(7 "B.SilkS" user "Ref Des/Silkscreen Bottom")
		(1 "F.Mask" user "Board Geometry/Soldermask Top")
		(3 "B.Mask" user "Board Geometry/Soldermask Bottom")
		(17 "Dwgs.User" user "User.Drawings")
		(19 "Cmts.User" user "User.Comments")
		(21 "Eco1.User" user "User.Eco1")
		(23 "Eco2.User" user "User.Eco2")
		(25 "Edge.Cuts" user "Board Geometry/Outline")
		(27 "Margin" user)
		(31 "F.CrtYd" user "Package Geometry/Place Bound Top")
		(29 "B.CrtYd" user "Package Geometry/Place Bound Bottom")
		(35 "F.Fab" user "Ref Des/Assembly Top")
		(33 "B.Fab" user "Ref Des/Assembly Bottom")
	)
	(footprint ""
		(layer "B.Cu")
		(at 119.418354 -388.011162 -90)
		(property "Reference" "C463"
			(at 0 0 90)
			(layer "B.SilkS")
			(hide yes)
			(effects
				(font
					(size 1.27 1.27)
				)
				(justify mirror)
			)
		)
		(property "Value" ""
			(at 0 0 90)
			(layer "B.Fab")
			(effects
				(font
					(size 1.27 1.27)
				)
				(justify mirror)
			)
		)
		(duplicate_pad_numbers_are_jumpers no)
		(fp_line
			(start -0.299974 0.150114)
			(end 0.299974 0.150114)
			(stroke
				(width 0.1)
				(type default)
			)
			(layer "B.Fab")
		)
		(fp_line
			(start 0.299974 0.150114)
			(end 0.299974 -0.150114)
			(stroke
				(width 0.1)
				(type default)
			)
			(layer "B.Fab")
		)
		(fp_line
			(start -0.299974 -0.150114)
			(end -0.299974 0.150114)
			(stroke
				(width 0.1)
				(type default)
			)
			(layer "B.Fab")
		)
		(fp_line
			(start 0.299974 -0.150114)
			(end -0.299974 -0.150114)
			(stroke
				(width 0.1)
				(type default)
			)
			(layer "B.Fab")
		)
		(pad "1" smd rect
			(at 0.2667 0 90)
			(size 0.3048 0.381)
			(layers "B.Cu" "B.Mask" "B.Paste")
			(net "P0V9_CPU1_RT3_2A_2D")
		)
		(pad "2" smd rect
			(at -0.2667 0 90)
			(size 0.3048 0.381)
			(layers "B.Cu" "B.Mask" "B.Paste")
			(net "GND")
		)
	)
	(footprint ""
		(layer "B.Cu")
		(at 396.797276 -177.294794 -90)
		(property "Reference" "PC589_1"
			(at 0 0 90)
			(layer "B.SilkS")
			(hide yes)
			(effects
				(font
					(size 1.27 1.27)
				)
				(justify mirror)
			)
		)
		(property "Value" ""
			(at 0 0 90)
			(layer "B.Fab")
			(effects
				(font
					(size 1.27 1.27)
				)
				(justify mirror)
			)
		)
		(duplicate_pad_numbers_are_jumpers no)
		(fp_line
			(start -1.524 0.762)
			(end 1.524 0.762)
			(stroke
				(width 0.1524)
				(type default)
			)
			(layer "B.SilkS")
		)
		(fp_line
			(start 1.524 0.762)
			(end 1.524 -0.762)
			(stroke
				(width 0.1524)
				(type default)
			)
			(layer "B.SilkS")
		)
		(fp_line
			(start -1.524 -0.762)
			(end -1.524 0.762)
			(stroke
				(width 0.1524)
				(type default)
			)
			(layer "B.SilkS")
		)
		(fp_line
			(start 1.524 -0.762)
			(end -1.524 -0.762)
			(stroke
				(width 0.1524)
				(type default)
			)
			(layer "B.SilkS")
		)
		(fp_line
			(start -1.1049 0.724916)
			(end -1.1049 -0.724916)
			(stroke
				(width 0.1)
				(type default)
			)
			(layer "B.Fab")
		)
		(fp_line
			(start 1.1049 0.724916)
			(end -1.1049 0.724916)
			(stroke
				(width 0.1)
				(type default)
			)
			(layer "B.Fab")
		)
		(fp_line
			(start -1.1049 -0.724916)
			(end 1.1049 -0.724916)
			(stroke
				(width 0.1)
				(type default)
			)
			(layer "B.Fab")
		)
		(fp_line
			(start 1.1049 -0.724916)
			(end 1.1049 0.724916)
			(stroke
				(width 0.1)
				(type default)
			)
			(layer "B.Fab")
		)
		(pad "1" smd rect
			(at 0.889 0 270)
			(size 1.016 1.27)
			(layers "B.Cu" "B.Mask" "B.Paste")
			(net "SW_P12V_AUX_PVDDCR_SOC_P0_FLT")
		)
		(pad "2" smd rect
			(at -0.889 0 270)
			(size 1.016 1.27)
			(layers "B.Cu" "B.Mask" "B.Paste")
			(net "GND")
		)
	)
	(footprint ""
		(layer "B.Cu")
		(at 323.039994 -337.653376 -90)
		(property "Reference" "PR83"
			(at 0 0 90)
			(layer "B.SilkS")
			(hide yes)
			(effects
				(font
					(size 1.27 1.27)
				)
				(justify mirror)
			)
		)
		(property "Value" ""
			(at 0 0 90)
			(layer "B.Fab")
			(effects
				(font
					(size 1.27 1.27)
				)
				(justify mirror)
			)
		)
		(duplicate_pad_numbers_are_jumpers no)
		(fp_line
			(start -0.7874 0.4064)
			(end 0.7874 0.4064)
			(stroke
				(width 0.1524)
				(type default)
			)
			(layer "B.SilkS")
		)
		(fp_line
			(start 0.7874 0.4064)
			(end 0.7874 -0.4064)
			(stroke
				(width 0.1524)
				(type default)
			)
			(layer "B.SilkS")
		)
		(fp_line
			(start -0.7874 -0.4064)
			(end -0.7874 0.4064)
			(stroke
				(width 0.1524)
				(type default)
			)
			(layer "B.SilkS")
		)
		(fp_line
			(start 0.7874 -0.4064)
			(end -0.7874 -0.4064)
			(stroke
				(width 0.1524)
				(type default)
			)
			(layer "B.SilkS")
		)
		(fp_line
			(start -0.67945 0.3048)
			(end -0.120396 0.3048)
			(stroke
				(width 0.1)
				(type default)
			)
			(layer "B.Fab")
		)
		(fp_line
			(start -0.120396 0.3048)
			(end -0.120396 0.2794)
			(stroke
				(width 0.1)
				(type default)
			)
			(layer "B.Fab")
		)
		(fp_line
			(start 0.12065 0.3048)
			(end 0.67945 0.3048)
			(stroke
				(width 0.1)
				(type default)
			)
			(layer "B.Fab")
		)
		(fp_line
			(start 0.67945 0.3048)
			(end 0.67945 -0.305054)
			(stroke
				(width 0.1)
				(type default)
			)
			(layer "B.Fab")
		)
		(fp_line
			(start -0.120396 0.2794)
			(end 0.12065 0.2794)
			(stroke
				(width 0.1)
				(type default)
			)
			(layer "B.Fab")
		)
		(fp_line
			(start 0.12065 0.2794)
			(end 0.12065 0.3048)
			(stroke
				(width 0.1)
				(type default)
			)
			(layer "B.Fab")
		)
		(fp_line
			(start -0.12065 -0.2794)
			(end -0.12065 -0.3048)
			(stroke
				(width 0.1)
				(type default)
			)
			(layer "B.Fab")
		)
		(fp_line
			(start 0.12065 -0.2794)
			(end -0.12065 -0.2794)
			(stroke
				(width 0.1)
				(type default)
			)
			(layer "B.Fab")
		)
		(fp_line
			(start -0.67945 -0.3048)
			(end -0.67945 0.3048)
			(stroke
				(width 0.1)
				(type default)
			)
			(layer "B.Fab")
		)
		(fp_line
			(start -0.12065 -0.3048)
			(end -0.67945 -0.3048)
			(stroke
				(width 0.1)
				(type default)
			)
			(layer "B.Fab")
		)
		(fp_line
			(start 0.12065 -0.305054)
			(end 0.12065 -0.2794)
			(stroke
				(width 0.1)
				(type default)
			)
			(layer "B.Fab")
		)
		(fp_line
			(start 0.67945 -0.305054)
			(end 0.12065 -0.305054)
			(stroke
				(width 0.1)
				(type default)
			)
			(layer "B.Fab")
		)
		(pad "1" smd circle
			(at 0.40005 0 90)
			(size 0 0)
			(layers "B.Cu" "B.Mask" "B.Paste")
			(net "PVDDCR_CPU1_P0_VOS2")
		)
		(pad "2" smd circle
			(at -0.40005 0 90)
			(size 0 0)
			(layers "B.Cu" "B.Mask" "B.Paste")
			(net "PVDDCR_CPU1_P0")
		)
	)
	(footprint ""
		(layer "B.Cu")
		(at 66.583814 -386.766562 90)
		(property "Reference" "C280"
			(at 0 0 90)
			(layer "B.SilkS")
			(hide yes)
			(effects
				(font
					(size 1.27 1.27)
				)
				(justify mirror)
			)
		)
		(property "Value" ""
			(at 0 0 90)
			(layer "B.Fab")
			(effects
				(font
					(size 1.27 1.27)
				)
				(justify mirror)
			)
		)
		(duplicate_pad_numbers_are_jumpers no)
		(fp_line
			(start 0.299974 -0.150114)
			(end -0.299974 -0.150114)
			(stroke
				(width 0.1)
				(type default)
			)
			(layer "B.Fab")
		)
		(fp_line
			(start -0.299974 -0.150114)
			(end -0.299974 0.150114)
			(stroke
				(width 0.1)
				(type default)
			)
			(layer "B.Fab")
		)
		(fp_line
			(start 0.299974 0.150114)
			(end 0.299974 -0.150114)
			(stroke
				(width 0.1)
				(type default)
			)
			(layer "B.Fab")
		)
		(fp_line
			(start -0.299974 0.150114)
			(end 0.299974 0.150114)
			(stroke
				(width 0.1)
				(type default)
			)
			(layer "B.Fab")
		)
		(pad "1" smd rect
			(at 0.2667 0 270)
			(size 0.3048 0.381)
			(layers "B.Cu" "B.Mask" "B.Paste")
			(net "P0V9_CPU1_RT0_2A")
		)
		(pad "2" smd rect
			(at -0.2667 0 270)
			(size 0.3048 0.381)
			(layers "B.Cu" "B.Mask" "B.Paste")
			(net "GND")
		)
	)
)
